# T6G (Grand Teton) — schematic netlist excerpt (pin names and nets, part order shuffled) for the footprints in the layout excerpt that follows; sources: Cadence DE-HDL packaged netlist, KiCad conversion of 04192023_DAF0TMB3IC0_F0TG_MB_C_brd_V02_OCP.brd

J24  SCONN288_DDR506112002KQ  IO  pkg DDR288S_1-1VXC  page 98
  VIN_BULK0  = P12V_MEM_CPU1
  RFU0  = NC
  VIN_MGMT  = P3V3_AUX
  HSCL  = I3C_SPD_DDRA_CPU1_SCL
  HSDA  = I3C_SPD_DDRA_CPU1_SDA
  VSS0  = GND
  DQ0_A  = M_A_CPU1_SA_DQ<0>
  VSS1  = GND
  DQ1_A  = M_A_CPU1_SA_DQ<1>
  VSS2  = GND
  DQS0_A_T  = M_A_CPU1_SA_DQS_DP<0>
  DQS0_A_C  = M_A_CPU1_SA_DQS_DN<0>
  VSS3  = GND
  DQ4_A  = M_A_CPU1_SA_DQ<4>
  VSS4  = GND
  DQ5_A  = M_A_CPU1_SA_DQ<5>
  VSS5  = GND
  DQ8_A  = M_A_CPU1_SA_DQ<8>
  VSS6  = GND
  DQ9_A  = M_A_CPU1_SA_DQ<9>
  VSS7  = GND
  DQS1_A_T  = M_A_CPU1_SA_DQS_DP<1>
  DQS1_A_C  = M_A_CPU1_SA_DQS_DN<1>
  VSS8  = GND
  DQ12_A  = M_A_CPU1_SA_DQ<12>
  VSS9  = GND
  DQ13_A  = M_A_CPU1_SA_DQ<13>
  VSS10  = GND
  DQ16_A  = M_A_CPU1_SA_DQ<16>
  VSS11  = GND
  DQ17_A  = M_A_CPU1_SA_DQ<17>
  VSS12  = GND
  DQS2_A_T  = M_A_CPU1_SA_DQS_DP<2>
  DQS2_A_C  = M_A_CPU1_SA_DQS_DN<2>
  VSS13  = GND
  DQ20_A  = M_A_CPU1_SA_DQ<20>
  VSS14  = GND
  DQ21_A  = M_A_CPU1_SA_DQ<21>
  VSS15  = GND
  DQ24_A  = M_A_CPU1_SA_DQ<24>
  VSS16  = GND
  DQ25_A  = M_A_CPU1_SA_DQ<25>
  VSS17  = GND
  DQS3_A_T  = M_A_CPU1_SA_DQS_DP<3>
  DQS3_A_C  = M_A_CPU1_SA_DQS_DN<3>
  VSS18  = GND
  DQ28_A  = M_A_CPU1_SA_DQ<28>
  VSS19  = GND
  DQ29_A  = M_A_CPU1_SA_DQ<29>
  VSS20  = GND
  CB0_A  = M_A_CPU1_SA_CB<0>
  VSS21  = GND
  CB1_A  = M_A_CPU1_SA_CB<1>
  VSS22  = GND
  DQS4_A_T  = M_A_CPU1_SA_DQS_DP<4>
  DQS4_A_C  = M_A_CPU1_SA_DQS_DN<4>
  VSS23  = GND
  CB4_A  = M_A_CPU1_SA_CB<4>
  VSS24  = GND
  CB5_A  = M_A_CPU1_SA_CB<5>
  VSS25  = GND
  ALERT_N  = M_A_CPU1_ALERT_N
  VSS26  = GND
  CS0_A_N  = M_A_CPU1_SA_CS_N<0>
  VSS27  = GND
  CA0_A  = M_A_CPU1_SA_CA<0>
  VSS28  = GND
  CA2_A  = M_A_CPU1_SA_CA<2>
  VSS29  = GND
  CA4_A  = M_A_CPU1_SA_CA<4>
  VSS30  = GND
  CA6_A  = M_A_CPU1_SA_CA<6>
  VSS31  = GND
  PAR_A  = M_A_CPU1_SA_PAR
  VSS32  = GND
  CA0_B  = M_A_CPU1_SB_CA<0>
  VSS33  = GND
  CA2_B  = M_A_CPU1_SB_CA<2>
  VSS34  = GND
  CA4_B  = M_A_CPU1_SB_CA<4>
  VSS35  = GND
  CA6_B  = M_A_CPU1_SB_CA<6>
  VSS36  = GND
  CS0_B_N  = M_A_CPU1_SB_CS_N<0>
  VSS37  = GND
  \lbd||rsp_a_n\  = M_A_CPU1_SA_RSP<0>
  \lbs||rsp_b_n\  = M_A_CPU1_SB_RSP<0>
  VSS38  = GND
  CB4_B  = M_A_CPU1_SB_CB<4>
  VSS39  = GND
  CB5_B  = M_A_CPU1_SB_CB<5>
  VSS40  = GND
  \dqs9_b_t||tdqs9_b_t||dbi4_b_n\  = M_A_CPU1_SB_DQS_DP<9>
  \dqs9_b_c||tdqs9_b_c\  = M_A_CPU1_SB_DQS_DN<9>
  VSS41  = GND
  CB0_B  = M_A_CPU1_SB_CB<0>
  VSS42  = GND
  CB1_B  = M_A_CPU1_SB_CB<1>
  VSS43  = GND
  DQ0_B  = M_A_CPU1_SB_DQ<0>
  VSS44  = GND
  DQ1_B  = M_A_CPU1_SB_DQ<1>
  VSS45  = GND
  DQS0_B_T  = M_A_CPU1_SB_DQS_DP<0>
  DQS0_B_C  = M_A_CPU1_SB_DQS_DN<0>
  VSS46  = GND
  DQ4_B  = M_A_CPU1_SB_DQ<4>
  VSS47  = GND
  DQ5_B  = M_A_CPU1_SB_DQ<5>
  VSS48  = GND
  DQ8_B  = M_A_CPU1_SB_DQ<8>
  VSS49  = GND
  DQ9_B  = M_A_CPU1_SB_DQ<9>
  VSS50  = GND
  DQS1_B_T  = M_A_CPU1_SB_DQS_DP<1>
  DQS1_B_C  = M_A_CPU1_SB_DQS_DN<1>
  VSS51  = GND
  DQ12_B  = M_A_CPU1_SB_DQ<12>
  VSS52  = GND
  DQ13_B  = M_A_CPU1_SB_DQ<13>
  VSS53  = GND
  DQ16_B  = M_A_CPU1_SB_DQ<16>
  VSS54  = GND
  DQ17_B  = M_A_CPU1_SB_DQ<17>
  VSS55  = GND
  DQS2_B_T  = M_A_CPU1_SB_DQS_DP<2>
  DQS2_B_C  = M_A_CPU1_SB_DQS_DN<2>
  VSS56  = GND
  DQ20_B  = M_A_CPU1_SB_DQ<20>
  VSS57  = GND
  DQ21_B  = M_A_CPU1_SB_DQ<21>
  VSS58  = GND
  DQ24_B  = M_A_CPU1_SB_DQ<24>
  VSS59  = GND
  DQ25_B  = M_A_CPU1_SB_DQ<25>
  VSS60  = GND
  DQS3_B_T  = M_A_CPU1_SB_DQS_DP<3>
  DQS3_B_C  = M_A_CPU1_SB_DQS_DN<3>
  VSS61  = GND
  DQ28_B  = M_A_CPU1_SB_DQ<28>
  VSS62  = GND
  DQ29_B  = M_A_CPU1_SB_DQ<29>
  VSS63  = GND
  RFU1  = NC
  VIN_BULK1  = P12V_MEM_CPU1
  VIN_BULK2  = P12V_MEM_CPU1
  \pwr_good||fail_n\  = PWRGD_CHA_CPU1_DIMM0
  HAS  = PD_CHA_CPU1_DIMM0_SAA
  RFU2  = NC
  RFU3  = NC
  VSS64  = GND
  DQ2_A  = M_A_CPU1_SA_DQ<2>
  VSS65  = GND
  DQ3_A  = M_A_CPU1_SA_DQ<3>
  VSS66  = GND
  \dqs5_a_c||tdqs5_a_c||dqs5_a_t||tdqs5_a_t\  = M_A_CPU1_SA_DQS_DN<5>
  \dqs5_a_t||tdqs5_a_t\  = M_A_CPU1_SA_DQS_DP<5>
  VSS67  = GND
  DQ6_A  = M_A_CPU1_SA_DQ<6>
  VSS68  = GND
  DQ7_A  = M_A_CPU1_SA_DQ<7>
  VSS69  = GND
  DQ10_A  = M_A_CPU1_SA_DQ<10>
  VSS70  = GND
  DQ11_A  = M_A_CPU1_SA_DQ<11>
  VSS71  = GND
  \dqs6_a_c||tdqs6_a_c||dqs6_a_t||tdqs6_a_t\  = M_A_CPU1_SA_DQS_DN<6>
  \dqs6_a_t||tdqs6_a_t\  = M_A_CPU1_SA_DQS_DP<6>
  VSS72  = GND
  DQ14_A  = M_A_CPU1_SA_DQ<14>
  VSS73  = GND
  DQ15_A  = M_A_CPU1_SA_DQ<15>
  VSS74  = GND
  DQ18_A  = M_A_CPU1_SA_DQ<18>
  VSS75  = GND
  DQ19_A  = M_A_CPU1_SA_DQ<19>
  VSS76  = GND
  \dqs7_a_c||tdqs7_a_c\  = M_A_CPU1_SA_DQS_DN<7>
  \dqs7_a_t||tdqs7_a_t\  = M_A_CPU1_SA_DQS_DP<7>
  VSS77  = GND
  DQ22_A  = M_A_CPU1_SA_DQ<22>
  VSS78  = GND
  DQ23_A  = M_A_CPU1_SA_DQ<23>
  VSS79  = GND
  DQ26_A  = M_A_CPU1_SA_DQ<26>
  VSS80  = GND
  DQ27_A  = M_A_CPU1_SA_DQ<27>
  VSS81  = GND
  \dqs8_a_c||tdqs8_a_c\  = M_A_CPU1_SA_DQS_DN<8>
  \dqs8_a_t||tdqs8_a_t\  = M_A_CPU1_SA_DQS_DP<8>
  VSS82  = GND
  DQ30_A  = M_A_CPU1_SA_DQ<30>
  VSS83  = GND
  DQ31_A  = M_A_CPU1_SA_DQ<31>
  VSS84  = GND
  CB2_A  = M_A_CPU1_SA_CB<2>
  VSS85  = GND
  CB3_A  = M_A_CPU1_SA_CB<3>
  VSS86  = GND
  \dqs9_a_c||tdqs9_a_c\  = M_A_CPU1_SA_DQS_DN<9>
  \dqs9_a_t||tdqs9_a_t\  = M_A_CPU1_SA_DQS_DP<9>
  VSS87  = GND
  CB6_A  = M_A_CPU1_SA_CB<6>
  VSS88  = GND
  CB7_A  = M_A_CPU1_SA_CB<7>
  VSS89  = GND
  RESET_N  = M_A_CPU1_RESET_N
  VSS90  = GND
  CS1_A_N  = M_A_CPU1_SA_CS_N<1>
  VSS91  = GND
  CA1_A  = M_A_CPU1_SA_CA<1>
  VSS92  = GND
  CA3_A  = M_A_CPU1_SA_CA<3>
  VSS93  = GND
  CA5_A  = M_A_CPU1_SA_CA<5>
  VSS94  = GND
  CK_T  = M_A_CPU1_CLK_DP<0>
  CK_C  = M_A_CPU1_CLK_DN<0>
  VSS95  = GND
  RFU4  = NC
  CA1_B  = M_A_CPU1_SB_CA<1>
  VSS96  = GND
  CA3_B  = M_A_CPU1_SB_CA<3>
  VSS97  = GND
  CA5_B  = M_A_CPU1_SB_CA<5>
  VSS98  = GND
  PAR_B  = M_A_CPU1_SB_PAR
  VSS99  = GND
  CS1_B_N  = M_A_CPU1_SB_CS_N<1>
  VSS100  = GND
  RFU5  = NC
  RFU6  = NC
  VSS101  = GND
  CB6_B  = M_A_CPU1_SB_CB<6>
  VSS102  = GND
  CB7_B  = M_A_CPU1_SB_CB<7>
  VSS103  = GND
  DQS4_B_C  = M_A_CPU1_SB_DQS_DN<4>
  DQS4_B_T  = M_A_CPU1_SB_DQS_DP<4>
  VSS104  = GND
  CB2_B  = M_A_CPU1_SB_CB<2>
  VSS105  = GND
  CB3_B  = M_A_CPU1_SB_CB<3>
  VSS106  = GND
  DQ2_B  = M_A_CPU1_SB_DQ<2>
  VSS107  = GND
  DQ3_B  = M_A_CPU1_SB_DQ<3>
  VSS108  = GND
  \dqs5_b_c||tdqs5_b_c\  = M_A_CPU1_SB_DQS_DN<5>
  \dqs5_b_t||tdqs5_b_t\  = M_A_CPU1_SB_DQS_DP<5>
  VSS109  = GND
  DQ6_B  = M_A_CPU1_SB_DQ<6>
  VSS110  = GND
  DQ7_B  = M_A_CPU1_SB_DQ<7>
  VSS111  = GND
  DQ10_B  = M_A_CPU1_SB_DQ<10>
  VSS112  = GND
  DQ11_B  = M_A_CPU1_SB_DQ<11>
  VSS113  = GND
  \dqs6_b_c||tdqs6_b_c\  = M_A_CPU1_SB_DQS_DN<6>
  \dqs6_b_t||tdqs6_b_t\  = M_A_CPU1_SB_DQS_DP<6>
  VSS114  = GND
  DQ14_B  = M_A_CPU1_SB_DQ<14>
  VSS115  = GND
  DQ15_B  = M_A_CPU1_SB_DQ<15>
  VSS116  = GND
  DQ18_B  = M_A_CPU1_SB_DQ<18>
  VSS117  = GND
  DQ19_B  = M_A_CPU1_SB_DQ<19>
  VSS118  = GND
  \dqs7_b_c||tdqs7_b_c\  = M_A_CPU1_SB_DQS_DN<7>
  \dqs7_b_t||tdqs7_b_t\  = M_A_CPU1_SB_DQS_DP<7>
  VSS119  = GND
  DQ22_B  = M_A_CPU1_SB_DQ<22>
  VSS120  = GND
  DQ23_B  = M_A_CPU1_SB_DQ<23>
  VSS121  = GND
  DQ26_B  = M_A_CPU1_SB_DQ<26>
  VSS122  = GND
  DQ27_B  = M_A_CPU1_SB_DQ<27>
  VSS123  = GND
  \dqs8_b_c||tdqs8_b_c\  = M_A_CPU1_SB_DQS_DN<8>
  \dqs8_b_t||tdqs8_b_t\  = M_A_CPU1_SB_DQS_DP<8>
  VSS124  = GND
  DQ30_B  = M_A_CPU1_SB_DQ<30>
  VSS125  = GND
  DQ31_B  = M_A_CPU1_SB_DQ<31>
  VSS126  = GND
  G1  = GND
  G2  = GND
  G3  = GND

(kicad_pcb
	(version 20260206)
	(generator "pcbnew")
	(generator_version "10.0")
	(general
		(thickness 1.6)
		(legacy_teardrops no)
	)
	(paper "A4")
	(title_block
		(title "04192023_DAF0TMB3IC0_F0TG_MB_C_brd_V02_OCP.brd")
		(comment 1 "Grand Teton / footprint 2100 of 8354 (J24), pads 139-184 of 291")
	)
	(layers
		(0 "F.Cu" signal "TOP")
		(4 "In1.Cu" signal "GND")
		(6 "In2.Cu" signal "IN1")
		(8 "In3.Cu" signal "GND1")
		(10 "In4.Cu" signal "IN2")
		(12 "In5.Cu" signal "GND2")
		(14 "In6.Cu" signal "IN3")
		(16 "In7.Cu" signal "GND3")
		(18 "In8.Cu" signal "VCC")
		(20 "In9.Cu" signal "VCC1")
		(22 "In10.Cu" signal "GND4")
		(24 "In11.Cu" signal "IN4")
		(26 "In12.Cu" signal "GND5")
		(28 "In13.Cu" signal "IN5")
		(30 "In14.Cu" signal "GND6")
		(32 "In15.Cu" signal "IN6")
		(34 "In16.Cu" signal "GND7")
		(2 "B.Cu" signal "BOTTOM")
		(9 "F.Adhes" user "F.Adhesive")
		(11 "B.Adhes" user "B.Adhesive")
		(13 "F.Paste" user "Package Geometry/Pastemask Top")
		(15 "B.Paste" user "Package Geometry/Pastemask Bottom")
		(5 "F.SilkS" user "Ref Des/Silkscreen Top")
		(7 "B.SilkS" user "Ref Des/Silkscreen Bottom")
		(1 "F.Mask" user "Board Geometry/Soldermask Top")
		(3 "B.Mask" user "Board Geometry/Soldermask Bottom")
		(17 "Dwgs.User" user "User.Drawings")
		(19 "Cmts.User" user "User.Comments")
		(21 "Eco1.User" user "User.Eco1")
		(23 "Eco2.User" user "User.Eco2")
		(25 "Edge.Cuts" user "Board Geometry/Outline")
		(27 "Margin" user)
		(31 "F.CrtYd" user "Package Geometry/Place Bound Top")
		(29 "B.CrtYd" user "Package Geometry/Place Bound Bottom")
		(35 "F.Fab" user "Ref Des/Assembly Top")
		(33 "B.Fab" user "Ref Des/Assembly Bottom")
	)
	(footprint ""
		(layer "F.Cu")
		(at 57.378092 -255.560322 180)
		(property "Reference" "J24"
			(at 1.914906 -84.58708 0)
			(unlocked yes)
			(layer "F.SilkS")
			(effects
				(font
					(size 0.7874 0.5842)
					(thickness 0.1524)
				)
			)
		)
		(property "Value" ""
			(at 0 0 180)
			(layer "F.Fab")
			(effects
				(font
					(size 1.27 1.27)
				)
			)
		)
		(duplicate_pad_numbers_are_jumpers no)
		(pad "139" smd rect
			(at -2.050034 59.075066 90)
			(size 0.519938 1.4986)
			(layers "F.Cu" "F.Mask" "F.Paste")
			(net "GND")
		)
		(pad "140" smd rect
			(at -2.050034 59.92495 90)
			(size 0.519938 1.4986)
			(layers "F.Cu" "F.Mask" "F.Paste")
			(net "M_A_CPU1_SB_DQ<28>")
		)
		(pad "141" smd rect
			(at -2.050034 60.775088 90)
			(size 0.519938 1.4986)
			(layers "F.Cu" "F.Mask" "F.Paste")
			(net "GND")
		)
		(pad "142" smd rect
			(at -2.050034 61.624972 90)
			(size 0.519938 1.4986)
			(layers "F.Cu" "F.Mask" "F.Paste")
			(net "M_A_CPU1_SB_DQ<29>")
		)
		(pad "143" smd rect
			(at -2.050034 62.47511 90)
			(size 0.519938 1.4986)
			(layers "F.Cu" "F.Mask" "F.Paste")
			(net "GND")
		)
		(pad "144" smd rect
			(at -2.050034 63.324994 90)
			(size 0.519938 1.4986)
			(layers "F.Cu" "F.Mask" "F.Paste")
			(net "Net_2257")
		)
		(pad "145" smd rect
			(at 2.050034 -63.324994 90)
			(size 0.519938 1.4986)
			(layers "F.Cu" "F.Mask" "F.Paste")
			(net "P12V_MEM_CPU1")
		)
		(pad "146" smd rect
			(at 2.050034 -62.47511 90)
			(size 0.519938 1.4986)
			(layers "F.Cu" "F.Mask" "F.Paste")
			(net "P12V_MEM_CPU1")
		)
		(pad "147" smd rect
			(at 2.050034 -61.624972 90)
			(size 0.519938 1.4986)
			(layers "F.Cu" "F.Mask" "F.Paste")
			(net "PWRGD_CHA_CPU1_DIMM0")
		)
		(pad "148" smd rect
			(at 2.050034 -60.775088 90)
			(size 0.519938 1.4986)
			(layers "F.Cu" "F.Mask" "F.Paste")
			(net "PD_CHA_CPU1_DIMM0_SAA")
		)
		(pad "149" smd rect
			(at 2.050034 -59.92495 90)
			(size 0.519938 1.4986)
			(layers "F.Cu" "F.Mask" "F.Paste")
			(net "Net_2258")
		)
		(pad "150" smd rect
			(at 2.050034 -59.075066 90)
			(size 0.519938 1.4986)
			(layers "F.Cu" "F.Mask" "F.Paste")
			(net "Net_2259")
		)
		(pad "151" smd rect
			(at 2.050034 -58.224928 90)
			(size 0.519938 1.4986)
			(layers "F.Cu" "F.Mask" "F.Paste")
			(net "GND")
		)
		(pad "152" smd rect
			(at 2.050034 -57.375044 90)
			(size 0.519938 1.4986)
			(layers "F.Cu" "F.Mask" "F.Paste")
			(net "M_A_CPU1_SA_DQ<2>")
		)
		(pad "153" smd rect
			(at 2.050034 -56.524906 90)
			(size 0.519938 1.4986)
			(layers "F.Cu" "F.Mask" "F.Paste")
			(net "GND")
		)
		(pad "154" smd rect
			(at 2.050034 -55.675022 90)
			(size 0.519938 1.4986)
			(layers "F.Cu" "F.Mask" "F.Paste")
			(net "M_A_CPU1_SA_DQ<3>")
		)
		(pad "155" smd rect
			(at 2.050034 -54.824884 90)
			(size 0.519938 1.4986)
			(layers "F.Cu" "F.Mask" "F.Paste")
			(net "GND")
		)
		(pad "156" smd rect
			(at 2.050034 -53.975 90)
			(size 0.519938 1.4986)
			(layers "F.Cu" "F.Mask" "F.Paste")
			(net "M_A_CPU1_SA_DQS_DN<5>")
		)
		(pad "157" smd rect
			(at 2.050034 -53.125116 90)
			(size 0.519938 1.4986)
			(layers "F.Cu" "F.Mask" "F.Paste")
			(net "M_A_CPU1_SA_DQS_DP<5>")
		)
		(pad "158" smd rect
			(at 2.050034 -52.274978 90)
			(size 0.519938 1.4986)
			(layers "F.Cu" "F.Mask" "F.Paste")
			(net "GND")
		)
		(pad "159" smd rect
			(at 2.050034 -51.425094 90)
			(size 0.519938 1.4986)
			(layers "F.Cu" "F.Mask" "F.Paste")
			(net "M_A_CPU1_SA_DQ<6>")
		)
		(pad "160" smd rect
			(at 2.050034 -50.574956 90)
			(size 0.519938 1.4986)
			(layers "F.Cu" "F.Mask" "F.Paste")
			(net "GND")
		)
		(pad "161" smd rect
			(at 2.050034 -49.725072 90)
			(size 0.519938 1.4986)
			(layers "F.Cu" "F.Mask" "F.Paste")
			(net "M_A_CPU1_SA_DQ<7>")
		)
		(pad "162" smd rect
			(at 2.050034 -48.874934 90)
			(size 0.519938 1.4986)
			(layers "F.Cu" "F.Mask" "F.Paste")
			(net "GND")
		)
		(pad "163" smd rect
			(at 2.050034 -48.02505 90)
			(size 0.519938 1.4986)
			(layers "F.Cu" "F.Mask" "F.Paste")
			(net "M_A_CPU1_SA_DQ<10>")
		)
		(pad "164" smd rect
			(at 2.050034 -47.174912 90)
			(size 0.519938 1.4986)
			(layers "F.Cu" "F.Mask" "F.Paste")
			(net "GND")
		)
		(pad "165" smd rect
			(at 2.050034 -46.325028 90)
			(size 0.519938 1.4986)
			(layers "F.Cu" "F.Mask" "F.Paste")
			(net "M_A_CPU1_SA_DQ<11>")
		)
		(pad "166" smd rect
			(at 2.050034 -45.47489 90)
			(size 0.519938 1.4986)
			(layers "F.Cu" "F.Mask" "F.Paste")
			(net "GND")
		)
		(pad "167" smd rect
			(at 2.050034 -44.625006 90)
			(size 0.519938 1.4986)
			(layers "F.Cu" "F.Mask" "F.Paste")
			(net "M_A_CPU1_SA_DQS_DN<6>")
		)
		(pad "168" smd rect
			(at 2.050034 -43.775122 90)
			(size 0.519938 1.4986)
			(layers "F.Cu" "F.Mask" "F.Paste")
			(net "M_A_CPU1_SA_DQS_DP<6>")
		)
		(pad "169" smd rect
			(at 2.050034 -42.924984 90)
			(size 0.519938 1.4986)
			(layers "F.Cu" "F.Mask" "F.Paste")
			(net "GND")
		)
		(pad "170" smd rect
			(at 2.050034 -42.0751 90)
			(size 0.519938 1.4986)
			(layers "F.Cu" "F.Mask" "F.Paste")
			(net "M_A_CPU1_SA_DQ<14>")
		)
		(pad "171" smd rect
			(at 2.050034 -41.224962 90)
			(size 0.519938 1.4986)
			(layers "F.Cu" "F.Mask" "F.Paste")
			(net "GND")
		)
		(pad "172" smd rect
			(at 2.050034 -40.375078 90)
			(size 0.519938 1.4986)
			(layers "F.Cu" "F.Mask" "F.Paste")
			(net "M_A_CPU1_SA_DQ<15>")
		)
		(pad "173" smd rect
			(at 2.050034 -39.52494 90)
			(size 0.519938 1.4986)
			(layers "F.Cu" "F.Mask" "F.Paste")
			(net "GND")
		)
		(pad "174" smd rect
			(at 2.050034 -38.675056 90)
			(size 0.519938 1.4986)
			(layers "F.Cu" "F.Mask" "F.Paste")
			(net "M_A_CPU1_SA_DQ<18>")
		)
		(pad "175" smd rect
			(at 2.050034 -37.824918 90)
			(size 0.519938 1.4986)
			(layers "F.Cu" "F.Mask" "F.Paste")
			(net "GND")
		)
		(pad "176" smd rect
			(at 2.050034 -36.975034 90)
			(size 0.519938 1.4986)
			(layers "F.Cu" "F.Mask" "F.Paste")
			(net "M_A_CPU1_SA_DQ<19>")
		)
		(pad "177" smd rect
			(at 2.050034 -36.124896 90)
			(size 0.519938 1.4986)
			(layers "F.Cu" "F.Mask" "F.Paste")
			(net "GND")
		)
		(pad "178" smd rect
			(at 2.050034 -35.275012 90)
			(size 0.519938 1.4986)
			(layers "F.Cu" "F.Mask" "F.Paste")
			(net "M_A_CPU1_SA_DQS_DN<7>")
		)
		(pad "179" smd rect
			(at 2.050034 -34.425128 90)
			(size 0.519938 1.4986)
			(layers "F.Cu" "F.Mask" "F.Paste")
			(net "M_A_CPU1_SA_DQS_DP<7>")
		)
		(pad "180" smd rect
			(at 2.050034 -33.57499 90)
			(size 0.519938 1.4986)
			(layers "F.Cu" "F.Mask" "F.Paste")
			(net "GND")
		)
		(pad "181" smd rect
			(at 2.050034 -32.725106 90)
			(size 0.519938 1.4986)
			(layers "F.Cu" "F.Mask" "F.Paste")
			(net "M_A_CPU1_SA_DQ<22>")
		)
		(pad "182" smd rect
			(at 2.050034 -31.874968 90)
			(size 0.519938 1.4986)
			(layers "F.Cu" "F.Mask" "F.Paste")
			(net "GND")
		)
		(pad "183" smd rect
			(at 2.050034 -31.025084 90)
			(size 0.519938 1.4986)
			(layers "F.Cu" "F.Mask" "F.Paste")
			(net "M_A_CPU1_SA_DQ<23>")
		)
		(pad "184" smd rect
			(at 2.050034 -30.174946 90)
			(size 0.519938 1.4986)
			(layers "F.Cu" "F.Mask" "F.Paste")
			(net "GND")
		)
	)
)
